# BASEBOARD_FAB2 (Tioga Pass) — schematic netlist excerpt (pin names and nets, part order shuffled) for the footprints in the layout excerpt that follows; sources: Cadence DE-HDL packaged netlist, KiCad conversion of Wiwynn_Tioga_Pass_MB.brd

R4G24  RES  0 5.0% CHIP  pkg 0603  page 233 : A = VR_PVPP_GHJ_BOOT ; B = VR_PVPP_GHJ_BOOT_R
R7D8  RES  10.0K 1% CHIP  pkg 0402  page 133 : A = P3V3_STBY ; B = PU_LPC_CLKRUN_N
R8F18  RES  0.0 5% CHIP  pkg 0402  page 185 : A = P3E_PCH_RX_0_DP ; B = P3E_PCH_M2_SATA6G_RX_R_DP

(kicad_pcb
	(version 20260206)
	(generator "pcbnew")
	(generator_version "10.0")
	(general
		(thickness 1.6)
		(legacy_teardrops no)
	)
	(paper "A4")
	(title_block
		(title "Wiwynn_Tioga_Pass_MB.brd")
		(comment 1 "Tioga Pass / footprints 618-620 of 4770")
	)
	(layers
		(0 "F.Cu" signal "TOP")
		(4 "In1.Cu" signal "L2GND")
		(6 "In2.Cu" signal "L3")
		(8 "In3.Cu" signal "L4GND")
		(10 "In4.Cu" signal "L5")
		(12 "In5.Cu" signal "L6GND")
		(14 "In6.Cu" signal "L7VCC")
		(16 "In7.Cu" signal "L8VCC")
		(18 "In8.Cu" signal "L9GND")
		(20 "In9.Cu" signal "L10")
		(22 "In10.Cu" signal "L11GND")
		(24 "In11.Cu" signal "L12")
		(26 "In12.Cu" signal "L13GND")
		(2 "B.Cu" signal "BOTTOM")
		(9 "F.Adhes" user "F.Adhesive")
		(11 "B.Adhes" user "B.Adhesive")
		(13 "F.Paste" user "Package Geometry/Pastemask Top")
		(15 "B.Paste" user "Package Geometry/Pastemask Bottom")
		(5 "F.SilkS" user "Ref Des/Silkscreen Top")
		(7 "B.SilkS" user "Ref Des/Silkscreen Bottom")
		(1 "F.Mask" user "Board Geometry/Soldermask Top")
		(3 "B.Mask" user "Board Geometry/Soldermask Bottom")
		(17 "Dwgs.User" user "User.Drawings")
		(19 "Cmts.User" user "User.Comments")
		(21 "Eco1.User" user "User.Eco1")
		(23 "Eco2.User" user "User.Eco2")
		(25 "Edge.Cuts" user "Board Geometry/Outline")
		(27 "Margin" user)
		(31 "F.CrtYd" user "Package Geometry/Place Bound Top")
		(29 "B.CrtYd" user "Package Geometry/Place Bound Bottom")
		(35 "F.Fab" user "Ref Des/Assembly Top")
		(33 "B.Fab" user "Ref Des/Assembly Bottom")
	)
	(footprint ""
		(layer "F.Cu")
		(at 379.2982 -29.232352 -90)
		(property "Reference" "R8F18"
			(at 0 0 270)
			(layer "F.SilkS")
			(hide yes)
			(effects
				(font
					(size 1.27 1.27)
				)
			)
		)
		(property "Value" ""
			(at 0 0 270)
			(layer "F.Fab")
			(effects
				(font
					(size 1.27 1.27)
				)
			)
		)
		(duplicate_pad_numbers_are_jumpers no)
		(fp_poly
			(pts
				(xy -0.2794 -0.1016) (xy 0.2794 -0.1016) (xy 0.2794 0.9906) (xy -0.2794 0.9906)
			)
			(stroke
				(width 0)
				(type default)
			)
			(fill no)
			(layer "F.CrtYd")
		)
		(fp_line
			(start -0.2794 0.9906)
			(end 0.2794 0.9906)
			(stroke
				(width 0.1)
				(type default)
			)
			(layer "F.Fab")
		)
		(fp_line
			(start 0.2794 0.9906)
			(end 0.2794 -0.1016)
			(stroke
				(width 0.1)
				(type default)
			)
			(layer "F.Fab")
		)
		(fp_line
			(start -0.2794 -0.1016)
			(end -0.2794 0.9906)
			(stroke
				(width 0.1)
				(type default)
			)
			(layer "F.Fab")
		)
		(fp_line
			(start 0.2794 -0.1016)
			(end -0.2794 -0.1016)
			(stroke
				(width 0.1)
				(type default)
			)
			(layer "F.Fab")
		)
		(pad "1" smd rect
			(at 0 0 270)
			(size 0.508 0.508)
			(layers "F.Cu" "F.Mask" "F.Paste")
			(net "P3E_PCH_RX_0_DP")
		)
		(pad "2" smd rect
			(at 0 0.889 270)
			(size 0.508 0.508)
			(layers "F.Cu" "F.Mask" "F.Paste")
			(net "P3E_PCH_M2_SATA6G_RX_R_DP")
		)
		(zone
			(layer "F.Cu")
			(hatch none 0.5)
			(connect_pads
				(clearance 0)
			)
			(min_thickness 0.25)
			(keepout
				(tracks not_allowed)
				(vias allowed)
				(pads allowed)
				(copperpour not_allowed)
				(footprints allowed)
			)
			(placement
				(enabled no)
				(sheetname "")
			)
			(fill
				(thermal_gap 0.5)
				(thermal_bridge_width 0.5)
				(island_removal_mode 0)
			)
			(polygon
				(pts
					(xy 378.6632 -29.486352) (xy 378.6632 -28.978352) (xy 379.0442 -28.978352) (xy 379.0442 -29.486352)
				)
			)
		)
		(zone
			(layer "F.Cu")
			(hatch none 0.5)
			(connect_pads
				(clearance 0)
			)
			(min_thickness 0.25)
			(keepout
				(tracks allowed)
				(vias not_allowed)
				(pads allowed)
				(copperpour not_allowed)
				(footprints allowed)
			)
			(placement
				(enabled no)
				(sheetname "")
			)
			(fill
				(thermal_gap 0.5)
				(thermal_bridge_width 0.5)
				(island_removal_mode 0)
			)
			(polygon
				(pts
					(xy 379.0442 -29.486352) (xy 379.0442 -28.978352) (xy 378.6632 -28.978352) (xy 378.6632 -29.486352)
				)
			)
		)
	)
	(footprint ""
		(layer "F.Cu")
		(at 173.093888 -10.255504 -90)
		(property "Reference" "R4G24"
			(at 1.01473 0.656336 180)
			(unlocked yes)
			(layer "F.SilkS")
			(effects
				(font
					(size 0.4064 0.254)
					(thickness 0.1524)
				)
			)
		)
		(property "Value" ""
			(at 0 0 270)
			(layer "F.Fab")
			(effects
				(font
					(size 1.27 1.27)
				)
			)
		)
		(duplicate_pad_numbers_are_jumpers no)
		(fp_poly
			(pts
				(xy -0.4953 -0.2032) (xy 0.4953 -0.2032) (xy 0.4953 1.6002) (xy -0.4953 1.6002)
			)
			(stroke
				(width 0)
				(type default)
			)
			(fill no)
			(layer "F.CrtYd")
		)
		(fp_line
			(start -0.4953 1.6002)
			(end -0.4953 -0.2032)
			(stroke
				(width 0.1)
				(type default)
			)
			(layer "F.Fab")
		)
		(fp_line
			(start 0.4953 1.6002)
			(end -0.4953 1.6002)
			(stroke
				(width 0.1)
				(type default)
			)
			(layer "F.Fab")
		)
		(fp_line
			(start -0.4953 -0.2032)
			(end 0.4953 -0.2032)
			(stroke
				(width 0.1)
				(type default)
			)
			(layer "F.Fab")
		)
		(fp_line
			(start 0.4953 -0.2032)
			(end 0.4953 1.6002)
			(stroke
				(width 0.1)
				(type default)
			)
			(layer "F.Fab")
		)
		(pad "1" smd rect
			(at 0 0 270)
			(size 0.762 0.889)
			(layers "F.Cu" "F.Mask" "F.Paste")
			(net "VR_PVPP_GHJ_BOOT")
		)
		(pad "2" smd rect
			(at 0 1.397 270)
			(size 0.762 0.889)
			(layers "F.Cu" "F.Mask" "F.Paste")
			(net "VR_PVPP_GHJ_BOOT_R")
		)
		(zone
			(layer "F.Cu")
			(hatch none 0.5)
			(connect_pads
				(clearance 0)
			)
			(min_thickness 0.25)
			(keepout
				(tracks not_allowed)
				(vias allowed)
				(pads allowed)
				(copperpour not_allowed)
				(footprints allowed)
			)
			(placement
				(enabled no)
				(sheetname "")
			)
			(fill
				(thermal_gap 0.5)
				(thermal_bridge_width 0.5)
				(island_removal_mode 0)
			)
			(polygon
				(pts
					(xy 172.141388 -10.636504) (xy 172.141388 -9.874504) (xy 172.649388 -9.874504) (xy 172.649388 -10.636504)
				)
			)
		)
		(zone
			(layer "F.Cu")
			(hatch none 0.5)
			(connect_pads
				(clearance 0)
			)
			(min_thickness 0.25)
			(keepout
				(tracks allowed)
				(vias not_allowed)
				(pads allowed)
				(copperpour not_allowed)
				(footprints allowed)
			)
			(placement
				(enabled no)
				(sheetname "")
			)
			(fill
				(thermal_gap 0.5)
				(thermal_bridge_width 0.5)
				(island_removal_mode 0)
			)
			(polygon
				(pts
					(xy 172.141388 -9.874504) (xy 172.649388 -9.874504) (xy 172.649388 -10.636504) (xy 172.141388 -10.636504)
				)
			)
		)
	)
	(footprint ""
		(layer "F.Cu")
		(at 383.032 -87.3125 180)
		(property "Reference" "R7D8"
			(at 0 0 180)
			(layer "F.SilkS")
			(hide yes)
			(effects
				(font
					(size 1.27 1.27)
				)
			)
		)
		(property "Value" ""
			(at 0 0 180)
			(layer "F.Fab")
			(effects
				(font
					(size 1.27 1.27)
				)
			)
		)
		(duplicate_pad_numbers_are_jumpers no)
		(fp_poly
			(pts
				(xy -0.2794 -0.1016) (xy 0.2794 -0.1016) (xy 0.2794 0.9906) (xy -0.2794 0.9906)
			)
			(stroke
				(width 0)
				(type default)
			)
			(fill no)
			(layer "F.CrtYd")
		)
		(fp_line
			(start 0.2794 0.9906)
			(end 0.2794 -0.1016)
			(stroke
				(width 0.1)
				(type default)
			)
			(layer "F.Fab")
		)
		(fp_line
			(start 0.2794 -0.1016)
			(end -0.2794 -0.1016)
			(stroke
				(width 0.1)
				(type default)
			)
			(layer "F.Fab")
		)
		(fp_line
			(start -0.2794 0.9906)
			(end 0.2794 0.9906)
			(stroke
				(width 0.1)
				(type default)
			)
			(layer "F.Fab")
		)
		(fp_line
			(start -0.2794 -0.1016)
			(end -0.2794 0.9906)
			(stroke
				(width 0.1)
				(type default)
			)
			(layer "F.Fab")
		)
		(pad "1" smd rect
			(at 0 0 180)
			(size 0.508 0.508)
			(layers "F.Cu" "F.Mask" "F.Paste")
			(net "P3V3_STBY")
		)
		(pad "2" smd rect
			(at 0 0.889 180)
			(size 0.508 0.508)
			(layers "F.Cu" "F.Mask" "F.Paste")
			(net "PU_LPC_CLKRUN_N")
		)
		(zone
			(layer "F.Cu")
			(hatch none 0.5)
			(connect_pads
				(clearance 0)
			)
			(min_thickness 0.25)
			(keepout
				(tracks not_allowed)
				(vias allowed)
				(pads allowed)
				(copperpour not_allowed)
				(footprints allowed)
			)
			(placement
				(enabled no)
				(sheetname "")
			)
			(fill
				(thermal_gap 0.5)
				(thermal_bridge_width 0.5)
				(island_removal_mode 0)
			)
			(polygon
				(pts
					(xy 383.286 -87.9475) (xy 382.778 -87.9475) (xy 382.778 -87.5665) (xy 383.286 -87.5665)
				)
			)
		)
		(zone
			(layer "F.Cu")
			(hatch none 0.5)
			(connect_pads
				(clearance 0)
			)
			(min_thickness 0.25)
			(keepout
				(tracks allowed)
				(vias not_allowed)
				(pads allowed)
				(copperpour not_allowed)
				(footprints allowed)
			)
			(placement
				(enabled no)
				(sheetname "")
			)
			(fill
				(thermal_gap 0.5)
				(thermal_bridge_width 0.5)
				(island_removal_mode 0)
			)
			(polygon
				(pts
					(xy 383.286 -87.5665) (xy 382.778 -87.5665) (xy 382.778 -87.9475) (xy 383.286 -87.9475)
				)
			)
		)
	)
)
